(kicad_pcb
	(version 20260206)
	(generator "pcbnew")
	(generator_version "10.0")
	(general
		(thickness 1.6)
		(legacy_teardrops no)
	)
	(paper "A4")
	(title_block
		(title "v1-tray-backplane — T6M_tray_BP_c_1023_1120.brd")
		(comment 1 "Open CloudServer (Microsoft) / footprint 93 of 170 (J16), pads 1-20 of 20")
	)
	(layers
		(0 "F.Cu" signal "TOP")
		(4 "In1.Cu" signal "GND")
		(6 "In2.Cu" signal "IN1")
		(8 "In3.Cu" signal "VCC")
		(10 "In4.Cu" signal "VCC1")
		(12 "In5.Cu" signal "IN2")
		(14 "In6.Cu" signal "GND1")
		(2 "B.Cu" signal "BOTTOM")
		(9 "F.Adhes" user "F.Adhesive")
		(11 "B.Adhes" user "B.Adhesive")
		(13 "F.Paste" user "Package Geometry/Pastemask Top")
		(15 "B.Paste" user "Package Geometry/Pastemask Bottom")
		(5 "F.SilkS" user "Ref Des/Silkscreen Top")
		(7 "B.SilkS" user "Ref Des/Silkscreen Bottom")
		(1 "F.Mask" user "Board Geometry/Soldermask Top")
		(3 "B.Mask" user "Board Geometry/Soldermask Bottom")
		(17 "Dwgs.User" user "User.Drawings")
		(19 "Cmts.User" user "User.Comments")
		(21 "Eco1.User" user "User.Eco1")
		(23 "Eco2.User" user "User.Eco2")
		(25 "Edge.Cuts" user "Board Geometry/Outline")
		(27 "Margin" user)
		(31 "F.CrtYd" user "Package Geometry/Place Bound Top")
		(29 "B.CrtYd" user "Package Geometry/Place Bound Bottom")
		(35 "F.Fab" user "Ref Des/Assembly Top")
		(33 "B.Fab" user "Ref Des/Assembly Bottom")
	)
	(footprint ""
		(layer "F.Cu")
		(at 149.615144 -49.795176)
		(property "Reference" "J16"
			(at 4.98475 2.618232 90)
			(unlocked yes)
			(layer "F.SilkS")
			(effects
				(font
					(size 0.7874 0.5842)
					(thickness 0.1524)
				)
				(justify left)
			)
		)
		(property "Value" ""
			(at 0 0 0)
			(layer "F.Fab")
			(effects
				(font
					(size 1.27 1.27)
				)
			)
		)
		(duplicate_pad_numbers_are_jumpers no)
		(pad "1" thru_hole circle
			(at 0 4.500118)
			(size 1.5494 1.5494)
			(drill 1.0414)
			(layers "*.Cu" "*.Mask")
			(remove_unused_layers no)
			(net "GND")
			(clearance 0)
		)
		(pad "2" thru_hole circle
			(at -8.58012 4.500118)
			(size 1.5494 1.5494)
			(drill 1.0414)
			(layers "*.Cu" "*.Mask")
			(remove_unused_layers no)
			(net "GND")
			(clearance 0)
		)
		(pad "3" thru_hole circle
			(at 0 14.500098)
			(size 1.5494 1.5494)
			(drill 1.0414)
			(layers "*.Cu" "*.Mask")
			(remove_unused_layers no)
			(net "GND")
			(clearance 0)
		)
		(pad "4" thru_hole circle
			(at -14.249908 9.500108)
			(size 1.5494 1.5494)
			(drill 1.0414)
			(layers "*.Cu" "*.Mask")
			(remove_unused_layers no)
			(net "GND")
			(clearance 0)
		)
		(pad "5" thru_hole circle
			(at -14.249908 19.500088)
			(size 1.5494 1.5494)
			(drill 1.0414)
			(layers "*.Cu" "*.Mask")
			(remove_unused_layers no)
			(net "GND")
			(clearance 0)
		)
		(pad "6" thru_hole circle
			(at 0 24.500078)
			(size 1.5494 1.5494)
			(drill 1.0414)
			(layers "*.Cu" "*.Mask")
			(remove_unused_layers no)
			(net "GND")
			(clearance 0)
		)
		(pad "7" thru_hole circle
			(at -5.679948 24.500078)
			(size 1.5494 1.5494)
			(drill 1.0414)
			(layers "*.Cu" "*.Mask")
			(remove_unused_layers no)
			(net "GND")
			(clearance 0)
		)
		(pad "8" thru_hole circle
			(at -11.079988 24.500078)
			(size 1.5494 1.5494)
			(drill 1.0414)
			(layers "*.Cu" "*.Mask")
			(remove_unused_layers no)
			(net "GND")
			(clearance 0)
		)
		(pad "9" thru_hole circle
			(at -14.249908 29.500068)
			(size 1.5494 1.5494)
			(drill 1.0414)
			(layers "*.Cu" "*.Mask")
			(remove_unused_layers no)
			(net "GND")
			(clearance 0)
		)
		(pad "10" thru_hole circle
			(at -14.249908 39.500048)
			(size 1.5494 1.5494)
			(drill 1.0414)
			(layers "*.Cu" "*.Mask")
			(remove_unused_layers no)
			(net "GND")
			(clearance 0)
		)
		(pad "11" thru_hole circle
			(at 0 27.29992)
			(size 1.3462 1.3462)
			(drill 0.9398)
			(layers "*.Cu" "*.Mask")
			(remove_unused_layers no)
			(net "GND")
			(clearance 0.0508)
			(thermal_gap 0.0508)
		)
		(pad "12" thru_hole circle
			(at 0 31.999936)
			(size 1.3462 1.3462)
			(drill 0.9398)
			(layers "*.Cu" "*.Mask")
			(remove_unused_layers no)
			(net "GND")
			(clearance 0.0508)
			(thermal_gap 0.0508)
		)
		(pad "13" thru_hole circle
			(at 0 36.999926)
			(size 1.3462 1.3462)
			(drill 0.9398)
			(layers "*.Cu" "*.Mask")
			(remove_unused_layers no)
			(net "GND")
			(clearance 0.0508)
			(thermal_gap 0.0508)
		)
		(pad "14" thru_hole circle
			(at -2.329942 41.60012)
			(size 1.3462 1.3462)
			(drill 0.9398)
			(layers "*.Cu" "*.Mask")
			(remove_unused_layers no)
			(net "GND")
			(clearance 0.0508)
			(thermal_gap 0.0508)
		)
		(pad "15" thru_hole circle
			(at -7.130034 41.60012)
			(size 1.3462 1.3462)
			(drill 0.9398)
			(layers "*.Cu" "*.Mask")
			(remove_unused_layers no)
			(net "GND")
			(clearance 0.0508)
			(thermal_gap 0.0508)
		)
		(pad "16" thru_hole circle
			(at -11.929872 41.60012)
			(size 1.3462 1.3462)
			(drill 0.9398)
			(layers "*.Cu" "*.Mask")
			(remove_unused_layers no)
			(net "GND")
			(clearance 0.0508)
			(thermal_gap 0.0508)
		)
		(pad "17" thru_hole circle
			(at -14.249908 27.29992)
			(size 1.3462 1.3462)
			(drill 0.9398)
			(layers "*.Cu" "*.Mask")
			(remove_unused_layers no)
			(net "GND")
			(clearance 0.0508)
			(thermal_gap 0.0508)
		)
		(pad "18" thru_hole circle
			(at -14.249908 31.999936)
			(size 1.3462 1.3462)
			(drill 0.9398)
			(layers "*.Cu" "*.Mask")
			(remove_unused_layers no)
			(net "GND")
			(clearance 0.0508)
			(thermal_gap 0.0508)
		)
		(pad "19" thru_hole circle
			(at -14.249908 36.999926)
			(size 1.3462 1.3462)
			(drill 0.9398)
			(layers "*.Cu" "*.Mask")
			(remove_unused_layers no)
			(net "GND")
			(clearance 0.0508)
			(thermal_gap 0.0508)
		)
		(pad "20" thru_hole circle
			(at 0 34.500058)
			(size 1.2446 1.2446)
			(drill 0.8382)
			(layers "*.Cu" "*.Mask")
			(remove_unused_layers no)
			(net "GND")
			(clearance 0.0508)
			(thermal_gap 0.0508)
		)
	)
)
